# S9S_MB_2U (Grand Teton) — schematic netlist excerpt (pin names and nets, part order shuffled) for the footprints in the layout excerpt that follows; sources: Cadence DE-HDL packaged netlist, KiCad conversion of 03242023_DA0F0TMBIJ0_F0T_Motherboard_J_brd_V01_OCP.brd

R2405  Q_RES  0 5% CHIP  pkg 0402LF  page 278 : A = IRQ_PVCCD_CPU0_VRHOT_LVC3_R_N ; B = IRQ_PVCCD_CPU0_VRHOT_LVC3_N
PC1183  Q_CAPP  560UF 2.5V 20% OSCON  pkg THLF  page 272 : A = PVCCFA_EHV_FIVRA_CPU0 ; B = GND
C513  Q_CAP  22UF 16V 20% X6S  pkg C0805  page 257 : A = PGPPA_AUX ; B = GND

(kicad_pcb
	(version 20260206)
	(generator "pcbnew")
	(generator_version "10.0")
	(general
		(thickness 1.6)
		(legacy_teardrops no)
	)
	(paper "A4")
	(title_block
		(title "03242023_DA0F0TMBIJ0_F0T_Motherboard_J_brd_V01_OCP.brd")
		(comment 1 "Grand Teton / footprints 51-53 of 6105")
	)
	(layers
		(0 "F.Cu" signal "TOP")
		(4 "In1.Cu" signal "GND")
		(6 "In2.Cu" signal "IN1")
		(8 "In3.Cu" signal "GND1")
		(10 "In4.Cu" signal "IN2")
		(12 "In5.Cu" signal "GND2")
		(14 "In6.Cu" signal "IN3")
		(16 "In7.Cu" signal "GND3")
		(18 "In8.Cu" signal "VCC")
		(20 "In9.Cu" signal "VCC1")
		(22 "In10.Cu" signal "GND4")
		(24 "In11.Cu" signal "IN4")
		(26 "In12.Cu" signal "GND5")
		(28 "In13.Cu" signal "IN5")
		(30 "In14.Cu" signal "GND6")
		(32 "In15.Cu" signal "IN6")
		(34 "In16.Cu" signal "GND7")
		(2 "B.Cu" signal "BOTTOM")
		(9 "F.Adhes" user "F.Adhesive")
		(11 "B.Adhes" user "B.Adhesive")
		(13 "F.Paste" user "Package Geometry/Pastemask Top")
		(15 "B.Paste" user "Package Geometry/Pastemask Bottom")
		(5 "F.SilkS" user "Ref Des/Silkscreen Top")
		(7 "B.SilkS" user "Ref Des/Silkscreen Bottom")
		(1 "F.Mask" user "Board Geometry/Soldermask Top")
		(3 "B.Mask" user "Board Geometry/Soldermask Bottom")
		(17 "Dwgs.User" user "User.Drawings")
		(19 "Cmts.User" user "User.Comments")
		(21 "Eco1.User" user "User.Eco1")
		(23 "Eco2.User" user "User.Eco2")
		(25 "Edge.Cuts" user "Board Geometry/Outline")
		(27 "Margin" user)
		(31 "F.CrtYd" user "Package Geometry/Place Bound Top")
		(29 "B.CrtYd" user "Package Geometry/Place Bound Bottom")
		(35 "F.Fab" user "Ref Des/Assembly Top")
		(33 "B.Fab" user "Ref Des/Assembly Bottom")
	)
	(footprint ""
		(layer "F.Cu")
		(at 421.292528 -346.017342)
		(property "Reference" "PC1183"
			(at 0 0 0)
			(layer "F.SilkS")
			(hide yes)
			(effects
				(font
					(size 1.27 1.27)
				)
			)
		)
		(property "Value" ""
			(at 0 0 0)
			(layer "F.Fab")
			(effects
				(font
					(size 1.27 1.27)
				)
			)
		)
		(duplicate_pad_numbers_are_jumpers no)
		(fp_line
			(start 2.750058 0.999998)
			(end -2.750058 0.999998)
			(stroke
				(width 0.1524)
				(type default)
			)
			(layer "F.SilkS")
		)
		(fp_circle
			(center 0 0.999998)
			(end 2.750058 0.999998)
			(stroke
				(width 0.1524)
				(type default)
			)
			(fill no)
			(layer "F.SilkS")
		)
		(fp_poly
			(pts
				(arc
					(start 2.750058 0.999998)
					(mid 0 3.750056)
					(end -2.750058 0.999998)
				)
			)
			(stroke
				(width 0)
				(type default)
			)
			(fill yes)
			(layer "F.SilkS")
		)
		(fp_circle
			(center 0 0.999998)
			(end 2.750058 0.999998)
			(stroke
				(width 0.1)
				(type default)
			)
			(fill no)
			(layer "F.Fab")
		)
		(pad "1" thru_hole rect
			(at 0 0)
			(size 1.5748 1.5748)
			(drill 1.0668)
			(layers "*.Cu" "*.Mask")
			(remove_unused_layers no)
			(net "PVCCFA_EHV_FIVRA_CPU0")
			(clearance 0)
			(padstack
				(mode front_inner_back)
				(layer "Inner"
					(shape circle)
					(size 1.5748 1.5748)
					(clearance 0)
				)
				(layer "B.Cu"
					(shape rect)
					(size 1.5748 1.5748)
					(clearance 0)
				)
			)
		)
		(pad "2" thru_hole circle
			(at 0 1.999996)
			(size 1.5748 1.5748)
			(drill 1.0668)
			(layers "*.Cu" "*.Mask")
			(remove_unused_layers no)
			(net "GND")
			(clearance 0)
		)
	)
	(footprint ""
		(layer "F.Cu")
		(at 327.281032 -15.829534)
		(property "Reference" "C513"
			(at 0 0 0)
			(layer "F.SilkS")
			(hide yes)
			(effects
				(font
					(size 1.27 1.27)
				)
			)
		)
		(property "Value" ""
			(at 0 0 0)
			(layer "F.Fab")
			(effects
				(font
					(size 1.27 1.27)
				)
			)
		)
		(duplicate_pad_numbers_are_jumpers no)
		(fp_line
			(start -1.524 -0.762)
			(end 1.524 -0.762)
			(stroke
				(width 0.1524)
				(type default)
			)
			(layer "F.SilkS")
		)
		(fp_line
			(start -1.524 0.762)
			(end -1.524 -0.762)
			(stroke
				(width 0.1524)
				(type default)
			)
			(layer "F.SilkS")
		)
		(fp_line
			(start 1.524 -0.762)
			(end 1.524 0.762)
			(stroke
				(width 0.1524)
				(type default)
			)
			(layer "F.SilkS")
		)
		(fp_line
			(start 1.524 0.762)
			(end -1.524 0.762)
			(stroke
				(width 0.1524)
				(type default)
			)
			(layer "F.SilkS")
		)
		(fp_line
			(start -1.1049 -0.724916)
			(end -1.1049 0.724916)
			(stroke
				(width 0.1)
				(type default)
			)
			(layer "F.Fab")
		)
		(fp_line
			(start -1.1049 0.724916)
			(end 1.1049 0.724916)
			(stroke
				(width 0.1)
				(type default)
			)
			(layer "F.Fab")
		)
		(fp_line
			(start 1.1049 -0.724916)
			(end -1.1049 -0.724916)
			(stroke
				(width 0.1)
				(type default)
			)
			(layer "F.Fab")
		)
		(fp_line
			(start 1.1049 0.724916)
			(end 1.1049 -0.724916)
			(stroke
				(width 0.1)
				(type default)
			)
			(layer "F.Fab")
		)
		(pad "1" smd rect
			(at -0.889 0 180)
			(size 1.016 1.27)
			(layers "F.Cu" "F.Mask" "F.Paste")
			(net "PGPPA_AUX")
		)
		(pad "2" smd rect
			(at 0.889 0 180)
			(size 1.016 1.27)
			(layers "F.Cu" "F.Mask" "F.Paste")
			(net "GND")
		)
	)
	(footprint ""
		(layer "F.Cu")
		(at 437.242966 -121.632726)
		(property "Reference" "R2405"
			(at 0 0 0)
			(layer "F.SilkS")
			(hide yes)
			(effects
				(font
					(size 1.27 1.27)
				)
			)
		)
		(property "Value" ""
			(at 0 0 0)
			(layer "F.Fab")
			(effects
				(font
					(size 1.27 1.27)
				)
			)
		)
		(duplicate_pad_numbers_are_jumpers no)
		(fp_line
			(start -0.7874 -0.4064)
			(end 0.7874 -0.4064)
			(stroke
				(width 0.1524)
				(type default)
			)
			(layer "F.SilkS")
		)
		(fp_line
			(start -0.7874 0.4064)
			(end -0.7874 -0.4064)
			(stroke
				(width 0.1524)
				(type default)
			)
			(layer "F.SilkS")
		)
		(fp_line
			(start 0.7874 -0.4064)
			(end 0.7874 0.4064)
			(stroke
				(width 0.1524)
				(type default)
			)
			(layer "F.SilkS")
		)
		(fp_line
			(start 0.7874 0.4064)
			(end -0.7874 0.4064)
			(stroke
				(width 0.1524)
				(type default)
			)
			(layer "F.SilkS")
		)
		(fp_line
			(start -0.67945 -0.305054)
			(end -0.12065 -0.305054)
			(stroke
				(width 0.1)
				(type default)
			)
			(layer "F.Fab")
		)
		(fp_line
			(start -0.67945 0.3048)
			(end -0.67945 -0.305054)
			(stroke
				(width 0.1)
				(type default)
			)
			(layer "F.Fab")
		)
		(fp_line
			(start -0.12065 -0.305054)
			(end -0.12065 -0.2794)
			(stroke
				(width 0.1)
				(type default)
			)
			(layer "F.Fab")
		)
		(fp_line
			(start -0.12065 -0.2794)
			(end 0.12065 -0.2794)
			(stroke
				(width 0.1)
				(type default)
			)
			(layer "F.Fab")
		)
		(fp_line
			(start -0.12065 0.2794)
			(end -0.12065 0.3048)
			(stroke
				(width 0.1)
				(type default)
			)
			(layer "F.Fab")
		)
		(fp_line
			(start -0.12065 0.3048)
			(end -0.67945 0.3048)
			(stroke
				(width 0.1)
				(type default)
			)
			(layer "F.Fab")
		)
		(fp_line
			(start 0.120396 0.2794)
			(end -0.12065 0.2794)
			(stroke
				(width 0.1)
				(type default)
			)
			(layer "F.Fab")
		)
		(fp_line
			(start 0.120396 0.3048)
			(end 0.120396 0.2794)
			(stroke
				(width 0.1)
				(type default)
			)
			(layer "F.Fab")
		)
		(fp_line
			(start 0.12065 -0.3048)
			(end 0.67945 -0.3048)
			(stroke
				(width 0.1)
				(type default)
			)
			(layer "F.Fab")
		)
		(fp_line
			(start 0.12065 -0.2794)
			(end 0.12065 -0.3048)
			(stroke
				(width 0.1)
				(type default)
			)
			(layer "F.Fab")
		)
		(fp_line
			(start 0.67945 -0.3048)
			(end 0.67945 0.3048)
			(stroke
				(width 0.1)
				(type default)
			)
			(layer "F.Fab")
		)
		(fp_line
			(start 0.67945 0.3048)
			(end 0.120396 0.3048)
			(stroke
				(width 0.1)
				(type default)
			)
			(layer "F.Fab")
		)
		(pad "1" smd circle
			(at -0.40005 0)
			(size 0 0)
			(layers "F.Cu" "F.Mask" "F.Paste")
			(net "IRQ_PVCCD_CPU0_VRHOT_LVC3_R_N")
		)
		(pad "2" smd circle
			(at 0.40005 0)
			(size 0 0)
			(layers "F.Cu" "F.Mask" "F.Paste")
			(net "IRQ_PVCCD_CPU0_VRHOT_LVC3_N")
		)
	)
)
